(kicad_pcb
	(version 20221018)
	(generator pcbnew)
	(general
    (thickness 1.518)
  )
	(paper "A4")
	(title_block
    (title "Kria K26 Devboard")
    (date "2024-03-26")
    (rev "1.2.5")
    (comment 1 "www.antmicro.com")
    (comment 2 "Antmicro Ltd.")
		(comment 9 "footprints 227-234 of 660")
	)
	(layers
    (0 "F.Cu" mixed)
    (1 "In1.Cu" power)
    (2 "In2.Cu" mixed)
    (3 "In3.Cu" power)
    (4 "In4.Cu" mixed)
    (5 "In5.Cu" power)
    (6 "In6.Cu" mixed)
    (31 "B.Cu" power)
    (32 "B.Adhes" user "B.Adhesive")
    (33 "F.Adhes" user "F.Adhesive")
    (34 "B.Paste" user)
    (35 "F.Paste" user)
    (36 "B.SilkS" user "B.Silkscreen")
    (37 "F.SilkS" user "F.Silkscreen")
    (38 "B.Mask" user)
    (39 "F.Mask" user)
    (40 "Dwgs.User" user "User.Drawings")
    (41 "Cmts.User" user "User.Comments")
    (42 "Eco1.User" user "User.Eco1")
    (43 "Eco2.User" user "User.Eco2")
    (44 "Edge.Cuts" user)
    (45 "Margin" user)
    (46 "B.CrtYd" user "B.Courtyard")
    (47 "F.CrtYd" user "F.Courtyard")
    (48 "B.Fab" user)
    (49 "F.Fab" user)
  )
	(footprint "kria-k26-devboard-footprints:UQFN-10_1.4x1.8x0.5mm_P0.4mm" (layer "F.Cu")
    (at 107.975 144.175 -90)
    (property "Author" "Antmicro")
    (property "License" "Apache-2.0")
    (property "MPN" "SN74AVC2T245RSWR")
    (property "Manufacturer" "Texas Instruments")
    (property "Sheetfile" "reset.kicad_sch")
    (property "Sheetname" "Reset logic")
    (property "ki_description" "Transceiver Non Inverting, AVC Family, 2 Input, 12 mA, 2.4 ns, 1.2 V to 3.6 V, LFCSP-10")
    (property "ki_keywords" "SMT, LOGIC, IC, LEVEL-SHIFTER, VOLTAGE")
    (attr smd)
    (fp_text reference "U34" (at 0.815 1.705 -90) (layer "F.SilkS")
        (effects (font (size 0.7 0.7) (thickness 0.15)) (justify left bottom))
    )
    (fp_text value "SN74AVC2T245_UQFN" (at 0 2.4 -90) (layer "F.Fab") hide
        (effects (font (size 0.7 0.7) (thickness 0.15)) (justify left bottom))
    )
    (fp_text user "${REFERENCE}" (at -0.657 4.498 -90) (layer "F.Fab") hide
        (effects (font (size 0.7 0.7) (thickness 0.15)) (justify left bottom))
    )
    (fp_text user "License: Apache-2.0" (at -0.657 6.9 -90) (layer "F.Fab") hide
        (effects (font (size 0.7 0.7) (thickness 0.15)) (justify left bottom))
    )
    (fp_text user "Author: Antmicro" (at -0.657 5.7 -90) (layer "F.Fab") hide
        (effects (font (size 0.7 0.7) (thickness 0.15)) (justify left bottom))
    )
    (fp_line (start -0.7305 -0.552) (end -1.2005 -0.552)
      (stroke (width 0.15) (type solid)) (layer "F.SilkS"))
    (fp_line (start -0.7305 -0.552) (end -0.7305 -0.93)
      (stroke (width 0.15) (type solid)) (layer "F.SilkS"))
    (fp_circle (center -1.0515 -1.151) (end -0.9805 -1.151)
      (stroke (width 0.15) (type solid)) (fill none) (layer "F.SilkS"))
    (fp_rect (start -1.3 -1.5) (end 1.3 1.5)
      (stroke (width 0.05) (type solid)) (fill none) (layer "F.CrtYd"))
    (fp_line (start -0.7 -0.4) (end -0.175 -0.925)
      (stroke (width 0.15) (type solid)) (layer "F.Fab"))
    (fp_line (start -0.7 0.93) (end -0.7 -0.4)
      (stroke (width 0.15) (type solid)) (layer "F.Fab"))
    (fp_line (start -0.175 -0.925) (end 0.7295 -0.925)
      (stroke (width 0.15) (type solid)) (layer "F.Fab"))
    (fp_line (start 0.725 0.93) (end -0.7 0.93)
      (stroke (width 0.15) (type solid)) (layer "F.Fab"))
    (fp_line (start 0.7295 -0.925) (end 0.725 0.93)
      (stroke (width 0.15) (type solid)) (layer "F.Fab"))
    (pad "1" smd roundrect (at -0.6445 -0.2 270) (size 0.81 0.22) (layers "F.Cu" "F.Paste" "F.Mask") (roundrect_rratio 0.25)
      (net 1 "GND") (pinfunction "DIR_{2}") (pintype "input"))
    (pad "2" smd roundrect (at -0.6445 0.2 270) (size 0.81 0.22) (layers "F.Cu" "F.Paste" "F.Mask") (roundrect_rratio 0.25)
      (net 161 "/Reset logic/PS_RST") (pinfunction "~{OE}") (pintype "input"))
    (pad "3" smd roundrect (at -0.4015 0.844 180) (size 0.81 0.22) (layers "F.Cu" "F.Paste" "F.Mask") (roundrect_rratio 0.25)
      (net 1 "GND") (pinfunction "GND") (pintype "power_in"))
    (pad "4" smd roundrect (at 0.0005 0.844 180) (size 0.81 0.22) (layers "F.Cu" "F.Paste" "F.Mask") (roundrect_rratio 0.25)
      (net 1 "GND") (pinfunction "B_{2}") (pintype "bidirectional"))
    (pad "5" smd roundrect (at 0.3995 0.844 180) (size 0.81 0.22) (layers "F.Cu" "F.Paste" "F.Mask") (roundrect_rratio 0.25)
      (net 224 "/Reset logic/MIO41") (pinfunction "B_{1}") (pintype "bidirectional"))
    (pad "6" smd roundrect (at 0.6455 0.2 270) (size 0.81 0.22) (layers "F.Cu" "F.Paste" "F.Mask") (roundrect_rratio 0.25)
      (net 17 "PS_1V8") (pinfunction "V_{CCB}") (pintype "power_in"))
    (pad "7" smd roundrect (at 0.6455 -0.2 270) (size 0.81 0.22) (layers "F.Cu" "F.Paste" "F.Mask") (roundrect_rratio 0.25)
      (net 15 "PS_3V3") (pinfunction "V_{CCA}") (pintype "power_in"))
    (pad "8" smd roundrect (at 0.3995 -0.847 180) (size 0.81 0.22) (layers "F.Cu" "F.Paste" "F.Mask") (roundrect_rratio 0.25)
      (net 676 "Net-(U34-A_{1})") (pinfunction "A_{1}") (pintype "bidirectional"))
    (pad "9" smd roundrect (at 0.0005 -0.847 180) (size 0.81 0.22) (layers "F.Cu" "F.Paste" "F.Mask") (roundrect_rratio 0.25)
      (net 732 "unconnected-(U34-A_{2}-Pad9)") (pinfunction "A_{2}") (pintype "bidirectional+no_connect"))
    (pad "10" smd roundrect (at -0.4015 -0.847 180) (size 0.81 0.22) (layers "F.Cu" "F.Paste" "F.Mask") (roundrect_rratio 0.25)
      (net 1 "GND") (pinfunction "DIR_{1}") (pintype "input"))
  )
	(footprint "kria-k26-devboard-footprints:TP_SMD_0.75mm" (layer "F.Cu")
    (at 98.9 137.3)
    (property "Author" "Antmicro")
    (property "License" "Apache-2.0")
    (property "MPN" "")
    (property "Manufacturer" "")
    (property "Sheetfile" "i2c.kicad_sch")
    (property "Sheetname" "I2C ")
    (property "ki_description" "Test Point 0.75mm")
    (attr exclude_from_pos_files)
    (fp_text reference "TP8" (at 0.33 2.32 90) (layer "F.SilkS")
        (effects (font (size 0.7 0.7) (thickness 0.15)) (justify left bottom))
    )
    (fp_text value "TP_0.75mm_SMD" (at 0 1.2) (layer "F.Fab") hide
        (effects (font (size 0.7 0.7) (thickness 0.15)) (justify left bottom))
    )
    (fp_text user "${REFERENCE}" (at -0.4 2.7) (layer "F.Fab") hide
        (effects (font (size 0.7 0.7) (thickness 0.15)) (justify left bottom))
    )
    (fp_text user "License: Apache-2.0" (at -0.4 5.101) (layer "F.Fab") hide
        (effects (font (size 0.7 0.7) (thickness 0.15)) (justify left bottom))
    )
    (fp_text user "Author: Antmicro" (at -0.4 3.901) (layer "F.Fab") hide
        (effects (font (size 0.7 0.7) (thickness 0.15)) (justify left bottom))
    )
    (pad "1" smd circle (at 0 0) (size 0.75 0.75) (layers "F.Cu" "F.Mask")
      (net 162 "/I2C /I2C_SCK_3V3") (pinfunction "1") (pintype "passive"))
  )
	(footprint "kria-k26-devboard-footprints:C_0402_1005Metric" (layer "F.Cu")
    (at 148.1 66.915 90)
    (descr "Capacitor SMD 0402")
    (tags "capacitor SMD 0402")
    (property "Author" "Antmicro")
    (property "Dielectric" "X5R")
    (property "License" "Apache-2.0")
    (property "MPN" "GRM155R61H104KE14D")
    (property "Manufacturer" "Murata")
    (property "Sheetfile" "supply-oring.kicad_sch")
    (property "Sheetname" "Supply ORing")
    (property "Val" "100n")
    (property "Voltage" "50V")
    (property "ki_description" " ")
    (attr smd)
    (fp_text reference "C229" (at -3.715 0.39 90) (layer "F.SilkS")
        (effects (font (size 0.7 0.7) (thickness 0.15)) (justify left bottom))
    )
    (fp_text value "C_100n_0402" (at 0 1.4 90) (layer "F.Fab") hide
        (effects (font (size 0.7 0.7) (thickness 0.15)) (justify left bottom))
    )
    (fp_text user "Author: Antmicro" (at -0.932 4.17 90) (layer "F.Fab") hide
        (effects (font (size 0.7 0.7) (thickness 0.15)) (justify left bottom))
    )
    (fp_text user "${REFERENCE}" (at -0.932 3.168 90) (layer "F.Fab") hide
        (effects (font (size 0.7 0.7) (thickness 0.15)) (justify left bottom))
    )
    (fp_text user "License: Apache-2.0" (at -0.932 5.17 90) (layer "F.Fab") hide
        (effects (font (size 0.7 0.7) (thickness 0.15)) (justify left bottom))
    )
    (fp_rect (start -0.94 -0.47) (end 0.94 0.47)
      (stroke (width 0.05) (type solid)) (fill none) (layer "F.CrtYd"))
    (fp_rect (start -0.499 -0.249) (end 0.499 0.249)
      (stroke (width 0.15) (type solid)) (fill none) (layer "F.Fab"))
    (pad "1" smd roundrect (at -0.484 0 90) (size 0.59 0.64) (layers "F.Cu" "F.Paste" "F.Mask") (roundrect_rratio 0.25)
      (net 14 "/Power Supply/DC/DC conventers/DC_MAIN_BUS") (pintype "passive"))
    (pad "2" smd roundrect (at 0.484 0 90) (size 0.59 0.64) (layers "F.Cu" "F.Paste" "F.Mask") (roundrect_rratio 0.25)
      (net 1 "GND") (pintype "passive"))
  )
	(footprint "kria-k26-devboard-footprints:LED_0603_1608Metric_G" (layer "F.Cu")
    (at 176.775 137.9 180)
    (descr "LED SMD 0603 Green")
    (tags "LED SMD 0603 Green")
    (property "Author" "Antmicro")
    (property "Color" "Green")
    (property "License" "Apache-2.0")
    (property "MPN" "LG L29K-G2J1-24-Z")
    (property "Manufacturer" "OSRAM")
    (property "Sheetfile" "dc-dc-conventers.kicad_sch")
    (property "Sheetname" "DC/DC conventers")
    (property "ki_description" "LED, Green, SMT, 0603, 20 mA, 2.1 V, 570 nm")
    (property "ki_keywords" "0603, SMT, DIODE, SEMICONDUCTOR, UNICOLOR")
    (attr smd)
    (fp_text reference "D19" (at 1.215 -0.45) (layer "F.SilkS")
        (effects (font (size 0.7 0.7) (thickness 0.15)) (justify right bottom))
    )
    (fp_text value "LED_G_0603_LG_L29K-G2J1-24-Z" (at 0 1.6) (layer "F.Fab") hide
        (effects (font (size 0.7 0.7) (thickness 0.15)) (justify right bottom))
    )
    (fp_text user "License: Apache-2.0" (at -1.31 5.769) (layer "F.Fab") hide
        (effects (font (size 0.7 0.7) (thickness 0.15)) (justify right bottom))
    )
    (fp_text user "${REFERENCE}" (at -1.31 3.769) (layer "F.Fab") hide
        (effects (font (size 0.7 0.7) (thickness 0.15)) (justify right bottom))
    )
    (fp_text user "Author: Antmicro" (at -1.31 4.769) (layer "F.Fab") hide
        (effects (font (size 0.7 0.7) (thickness 0.15)) (justify right bottom))
    )
    (fp_line (start -0.27 -0.35) (end 0.27 -0.35)
      (stroke (width 0.15) (type solid)) (layer "F.SilkS"))
    (fp_line (start -0.27 0.351) (end 0.27 0.351)
      (stroke (width 0.15) (type solid)) (layer "F.SilkS"))
    (fp_line (start -0.106328 -0.200008) (end -0.106328 0.199992)
      (stroke (width 0.1) (type solid)) (layer "F.SilkS"))
    (fp_line (start -0.106328 -0.200008) (end 0.093672 -0.000008)
      (stroke (width 0.1) (type solid)) (layer "F.SilkS"))
    (fp_line (start -0.106328 -0.000008) (end -0.29 0)
      (stroke (width 0.1) (type solid)) (layer "F.SilkS"))
    (fp_line (start 0.093672 -0.200008) (end 0.093672 0.199992)
      (stroke (width 0.1) (type solid)) (layer "F.SilkS"))
    (fp_line (start 0.093672 -0.000008) (end -0.106328 0.199992)
      (stroke (width 0.1) (type solid)) (layer "F.SilkS"))
    (fp_line (start 0.093672 -0.000008) (end 0.293672 -0.000008)
      (stroke (width 0.1) (type solid)) (layer "F.SilkS"))
    (fp_line (start 1.25 0.32) (end 1.25 -0.32)
      (stroke (width 0.15) (type solid)) (layer "F.SilkS"))
    (fp_rect (start 1.26 0.65) (end -1.26 -0.65)
      (stroke (width 0.05) (type solid)) (fill none) (layer "F.CrtYd"))
    (fp_line (start -0.599 0) (end -0.201 0)
      (stroke (width 0.15) (type solid)) (layer "F.Fab"))
    (fp_line (start -0.201 -0.2) (end -0.201 0)
      (stroke (width 0.15) (type solid)) (layer "F.Fab"))
    (fp_line (start -0.201 0) (end -0.201 0.202)
      (stroke (width 0.15) (type solid)) (layer "F.Fab"))
    (fp_line (start -0.201 0.202) (end 0.101 0)
      (stroke (width 0.15) (type solid)) (layer "F.Fab"))
    (fp_line (start 0.101 0) (end -0.201 -0.2)
      (stroke (width 0.15) (type solid)) (layer "F.Fab"))
    (fp_line (start 0.199 -0.2) (end 0.199 -0.1)
      (stroke (width 0.15) (type solid)) (layer "F.Fab"))
    (fp_line (start 0.199 0) (end 0.597 0)
      (stroke (width 0.15) (type solid)) (layer "F.Fab"))
    (fp_line (start 0.199 0.202) (end 0.199 -0.1)
      (stroke (width 0.15) (type solid)) (layer "F.Fab"))
    (fp_rect (start -0.848 -0.4) (end 0.85 0.402)
      (stroke (width 0.15) (type solid)) (fill none) (layer "F.Fab"))
    (pad "1" smd rect (at -0.75 0) (size 0.8 0.8) (layers "F.Cu" "F.Paste" "F.Mask")
      (net 191 "Net-(D19-Pad1)") (pintype "passive"))
    (pad "2" smd rect (at 0.75 0) (size 0.8 0.8) (layers "F.Cu" "F.Paste" "F.Mask")
      (net 1 "GND") (pinfunction "2") (pintype "passive"))
  )
	(footprint "kria-k26-devboard-footprints:R_0402_1005Metric" (layer "F.Cu")
    (at 131.8 117)
    (descr "Resistor SMD 0402")
    (tags "resistor SMD 0402")
    (property "Author" "Antmicro")
    (property "License" "Apache-2.0")
    (property "MPN" "CR0402-FX-1002GLF")
    (property "Manufacturer" "Bourns")
    (property "Sheetfile" "pcie-m2-key-e.kicad_sch")
    (property "Sheetname" "PCIE M2 key E ")
    (property "Tolerance" "1%")
    (property "Val" "10k")
    (property "ki_description" "10k resistor in 0402 package with 1% tolerance")
    (attr smd)
    (fp_text reference "R152" (at -1.27 -1.56) (layer "F.SilkS")
        (effects (font (size 0.7 0.7) (thickness 0.15)) (justify left bottom))
    )
    (fp_text value "R_10k_0402" (at 0 1.4) (layer "F.Fab") hide
        (effects (font (size 0.7 0.7) (thickness 0.15)) (justify left bottom))
    )
    (fp_text user "${REFERENCE}" (at -0.95 3.168) (layer "F.Fab") hide
        (effects (font (size 0.7 0.7) (thickness 0.15)) (justify left bottom))
    )
    (fp_text user "License: Apache-2.0" (at -0.95 5.169) (layer "F.Fab") hide
        (effects (font (size 0.7 0.7) (thickness 0.15)) (justify left bottom))
    )
    (fp_text user "Author: Antmicro" (at -0.95 4.169) (layer "F.Fab") hide
        (effects (font (size 0.7 0.7) (thickness 0.15)) (justify left bottom))
    )
    (fp_rect (start -0.93 -0.47) (end 0.93 0.47)
      (stroke (width 0.05) (type solid)) (fill none) (layer "F.CrtYd"))
    (fp_rect (start -0.5 -0.25) (end 0.5 0.25)
      (stroke (width 0.15) (type solid)) (fill none) (layer "F.Fab"))
    (pad "1" smd roundrect (at -0.485 0) (size 0.59 0.64) (layers "F.Cu" "F.Paste" "F.Mask") (roundrect_rratio 0.25)
      (net 15 "PS_3V3") (pintype "passive"))
    (pad "2" smd roundrect (at 0.485 0) (size 0.59 0.64) (layers "F.Cu" "F.Paste" "F.Mask") (roundrect_rratio 0.25)
      (net 227 "/PCIE M2 key E /~{M2_PEWAKE}") (pintype "passive"))
  )
	(footprint "kria-k26-devboard-footprints:SOT-416" (layer "F.Cu")
    (at 136.4 124.874999 180)
    (descr "SOT-416")
    (tags "SOT-416")
    (property "Author" "Antmicro")
    (property "License" "Apache-2.0")
    (property "MPN" "DTC014TEBTL")
    (property "Manufacturer" "ROHM Semiconductor")
    (property "Sheetfile" "debug.kicad_sch")
    (property "Sheetname" "Debug and JTAG")
    (property "ki_description" "Digital NPN Transistor, 10k/NONE, EMT-3")
    (attr smd)
    (fp_text reference "Q11" (at 2.78 0.504999) (layer "F.SilkS")
        (effects (font (size 0.7 0.7) (thickness 0.15)) (justify left bottom))
    )
    (fp_text value "DTC014T_SOT-416" (at 0 2 180) (layer "F.Fab") hide
        (effects (font (size 0.7 0.7) (thickness 0.15)) (justify left bottom))
    )
    (fp_text user "License: Apache-2.0" (at -1 5.802 180) (layer "F.Fab") hide
        (effects (font (size 0.7 0.7) (thickness 0.15)) (justify left bottom))
    )
    (fp_text user "${REFERENCE}" (at -1 3.4 180) (layer "F.Fab") hide
        (effects (font (size 0.7 0.7) (thickness 0.15)) (justify left bottom))
    )
    (fp_text user "Author: Antmicro" (at -1 4.602 180) (layer "F.Fab") hide
        (effects (font (size 0.7 0.7) (thickness 0.15)) (justify left bottom))
    )
    (fp_line (start -0.5 -0.15) (end -0.5 0.15)
      (stroke (width 0.15) (type solid)) (layer "F.SilkS"))
    (fp_line (start 0.5 0.9) (end -0.5 0.9)
      (stroke (width 0.15) (type solid)) (layer "F.SilkS"))
    (fp_line (start 0.5 0.9) (end 0.5 0.7)
      (stroke (width 0.15) (type solid)) (layer "F.SilkS"))
    (fp_line (start 0.508 -0.9) (end -0.5 -0.9)
      (stroke (width 0.15) (type solid)) (layer "F.SilkS"))
    (fp_line (start 0.508 -0.9) (end 0.508 -0.592)
      (stroke (width 0.15) (type solid)) (layer "F.SilkS"))
    (fp_rect (start -1 -1.05) (end 1 1.05)
      (stroke (width 0.05) (type solid)) (fill none) (layer "F.CrtYd"))
    (fp_line (start -0.05 -0.9) (end -0.45 -0.5)
      (stroke (width 0.15) (type solid)) (layer "F.Fab"))
    (fp_rect (start 0.45 0.9) (end -0.45 -0.9)
      (stroke (width 0.15) (type solid)) (fill none) (layer "F.Fab"))
    (pad "1" smd rect (at -0.652 -0.5 180) (size 0.6 0.5) (layers "F.Cu" "F.Paste" "F.Mask")
      (net 220 "/Debug and JTAG/CONN_GND") (pinfunction "B") (pintype "input"))
    (pad "2" smd rect (at -0.652 0.498 180) (size 0.6 0.5) (layers "F.Cu" "F.Paste" "F.Mask")
      (net 1 "GND") (pinfunction "E") (pintype "passive"))
    (pad "3" smd rect (at 0.65 0 180) (size 0.6 0.5) (layers "F.Cu" "F.Paste" "F.Mask")
      (net 160 "/Debug and JTAG/~{LS_OE}") (pinfunction "C") (pintype "passive"))
  )
	(footprint "kria-k26-devboard-footprints:R_0402_1005Metric" (layer "F.Cu")
    (at 136.595 123.23 180)
    (descr "Resistor SMD 0402")
    (tags "resistor SMD 0402")
    (property "Author" "Antmicro")
    (property "License" "Apache-2.0")
    (property "MPN" "CR0402-FX-1002GLF")
    (property "Manufacturer" "Bourns")
    (property "Sheetfile" "debug.kicad_sch")
    (property "Sheetname" "Debug and JTAG")
    (property "Tolerance" "1%")
    (property "Val" "10k")
    (property "ki_description" "10k resistor in 0402 package with 1% tolerance")
    (attr smd)
    (fp_text reference "R112" (at 3.675 -0.2 180) (layer "F.SilkS")
        (effects (font (size 0.7 0.7) (thickness 0.15)) (justify left bottom))
    )
    (fp_text value "R_10k_0402" (at 0 1.4 180) (layer "F.Fab") hide
        (effects (font (size 0.7 0.7) (thickness 0.15)) (justify left bottom))
    )
    (fp_text user "${REFERENCE}" (at -0.95 3.168 180) (layer "F.Fab") hide
        (effects (font (size 0.7 0.7) (thickness 0.15)) (justify left bottom))
    )
    (fp_text user "License: Apache-2.0" (at -0.95 5.169 180) (layer "F.Fab") hide
        (effects (font (size 0.7 0.7) (thickness 0.15)) (justify left bottom))
    )
    (fp_text user "Author: Antmicro" (at -0.95 4.169 180) (layer "F.Fab") hide
        (effects (font (size 0.7 0.7) (thickness 0.15)) (justify left bottom))
    )
    (fp_rect (start -0.93 -0.47) (end 0.93 0.47)
      (stroke (width 0.05) (type solid)) (fill none) (layer "F.CrtYd"))
    (fp_rect (start -0.5 -0.25) (end 0.5 0.25)
      (stroke (width 0.15) (type solid)) (fill none) (layer "F.Fab"))
    (pad "1" smd roundrect (at -0.485 0 180) (size 0.59 0.64) (layers "F.Cu" "F.Paste" "F.Mask") (roundrect_rratio 0.25)
      (net 138 "/Debug and JTAG/USB_3V3") (pintype "passive"))
    (pad "2" smd roundrect (at 0.485 0 180) (size 0.59 0.64) (layers "F.Cu" "F.Paste" "F.Mask") (roundrect_rratio 0.25)
      (net 160 "/Debug and JTAG/~{LS_OE}") (pintype "passive"))
  )
	(footprint "kria-k26-devboard-footprints:R_0402_1005Metric" (layer "F.Cu")
    (at 136.595 126.53 180)
    (descr "Resistor SMD 0402")
    (tags "resistor SMD 0402")
    (property "Author" "Antmicro")
    (property "License" "Apache-2.0")
    (property "MPN" "CR0402-FX-1002GLF")
    (property "Manufacturer" "Bourns")
    (property "Sheetfile" "debug.kicad_sch")
    (property "Sheetname" "Debug and JTAG")
    (property "Tolerance" "1%")
    (property "Val" "10k")
    (property "ki_description" "10k resistor in 0402 package with 1% tolerance")
    (attr smd)
    (fp_text reference "R111" (at 3.655 -0.4 180) (layer "F.SilkS")
        (effects (font (size 0.7 0.7) (thickness 0.15)) (justify left bottom))
    )
    (fp_text value "R_10k_0402" (at 0 1.4 180) (layer "F.Fab") hide
        (effects (font (size 0.7 0.7) (thickness 0.15)) (justify left bottom))
    )
    (fp_text user "Author: Antmicro" (at -0.95 4.169 180) (layer "F.Fab") hide
        (effects (font (size 0.7 0.7) (thickness 0.15)) (justify left bottom))
    )
    (fp_text user "License: Apache-2.0" (at -0.95 5.169 180) (layer "F.Fab") hide
        (effects (font (size 0.7 0.7) (thickness 0.15)) (justify left bottom))
    )
    (fp_text user "${REFERENCE}" (at -0.95 3.168 180) (layer "F.Fab") hide
        (effects (font (size 0.7 0.7) (thickness 0.15)) (justify left bottom))
    )
    (fp_rect (start -0.93 -0.47) (end 0.93 0.47)
      (stroke (width 0.05) (type solid)) (fill none) (layer "F.CrtYd"))
    (fp_rect (start -0.5 -0.25) (end 0.5 0.25)
      (stroke (width 0.15) (type solid)) (fill none) (layer "F.Fab"))
    (pad "1" smd roundrect (at -0.485 0 180) (size 0.59 0.64) (layers "F.Cu" "F.Paste" "F.Mask") (roundrect_rratio 0.25)
      (net 138 "/Debug and JTAG/USB_3V3") (pintype "passive"))
    (pad "2" smd roundrect (at 0.485 0 180) (size 0.59 0.64) (layers "F.Cu" "F.Paste" "F.Mask") (roundrect_rratio 0.25)
      (net 220 "/Debug and JTAG/CONN_GND") (pintype "passive"))
  )
)
